(kicad_pcb
	(version 20260206)
	(generator "pcbnew")
	(generator_version "10.0")
	(general
		(thickness 1.6)
		(legacy_teardrops no)
	)
	(paper "A4")
	(title_block
		(title "04192023_DAF0TMB3IC0_F0TG_MB_C_brd_V02_OCP.brd")
		(comment 1 "Grand Teton / footprint 2100 of 8354 (J24), pads 1-113 of 291")
	)
	(layers
		(0 "F.Cu" signal "TOP")
		(4 "In1.Cu" signal "GND")
		(6 "In2.Cu" signal "IN1")
		(8 "In3.Cu" signal "GND1")
		(10 "In4.Cu" signal "IN2")
		(12 "In5.Cu" signal "GND2")
		(14 "In6.Cu" signal "IN3")
		(16 "In7.Cu" signal "GND3")
		(18 "In8.Cu" signal "VCC")
		(20 "In9.Cu" signal "VCC1")
		(22 "In10.Cu" signal "GND4")
		(24 "In11.Cu" signal "IN4")
		(26 "In12.Cu" signal "GND5")
		(28 "In13.Cu" signal "IN5")
		(30 "In14.Cu" signal "GND6")
		(32 "In15.Cu" signal "IN6")
		(34 "In16.Cu" signal "GND7")
		(2 "B.Cu" signal "BOTTOM")
		(9 "F.Adhes" user "F.Adhesive")
		(11 "B.Adhes" user "B.Adhesive")
		(13 "F.Paste" user "Package Geometry/Pastemask Top")
		(15 "B.Paste" user "Package Geometry/Pastemask Bottom")
		(5 "F.SilkS" user "Ref Des/Silkscreen Top")
		(7 "B.SilkS" user "Ref Des/Silkscreen Bottom")
		(1 "F.Mask" user "Board Geometry/Soldermask Top")
		(3 "B.Mask" user "Board Geometry/Soldermask Bottom")
		(17 "Dwgs.User" user "User.Drawings")
		(19 "Cmts.User" user "User.Comments")
		(21 "Eco1.User" user "User.Eco1")
		(23 "Eco2.User" user "User.Eco2")
		(25 "Edge.Cuts" user "Board Geometry/Outline")
		(27 "Margin" user)
		(31 "F.CrtYd" user "Package Geometry/Place Bound Top")
		(29 "B.CrtYd" user "Package Geometry/Place Bound Bottom")
		(35 "F.Fab" user "Ref Des/Assembly Top")
		(33 "B.Fab" user "Ref Des/Assembly Bottom")
	)
	(footprint ""
		(layer "F.Cu")
		(at 57.378092 -255.560322 180)
		(property "Reference" "J24"
			(at 1.914906 -84.58708 0)
			(unlocked yes)
			(layer "F.SilkS")
			(effects
				(font
					(size 0.7874 0.5842)
					(thickness 0.1524)
				)
			)
		)
		(property "Value" ""
			(at 0 0 180)
			(layer "F.Fab")
			(effects
				(font
					(size 1.27 1.27)
				)
			)
		)
		(duplicate_pad_numbers_are_jumpers no)
		(pad "1" smd rect
			(at -2.050034 -63.324994 90)
			(size 0.519938 1.4986)
			(layers "F.Cu" "F.Mask" "F.Paste")
			(net "P12V_MEM_CPU1")
		)
		(pad "2" smd rect
			(at -2.050034 -62.47511 90)
			(size 0.519938 1.4986)
			(layers "F.Cu" "F.Mask" "F.Paste")
			(net "Net_2256")
		)
		(pad "3" smd rect
			(at -2.050034 -61.624972 90)
			(size 0.519938 1.4986)
			(layers "F.Cu" "F.Mask" "F.Paste")
			(net "P3V3_AUX")
		)
		(pad "4" smd rect
			(at -2.050034 -60.775088 90)
			(size 0.519938 1.4986)
			(layers "F.Cu" "F.Mask" "F.Paste")
			(net "I3C_SPD_DDRA_CPU1_SCL")
		)
		(pad "5" smd rect
			(at -2.050034 -59.92495 90)
			(size 0.519938 1.4986)
			(layers "F.Cu" "F.Mask" "F.Paste")
			(net "I3C_SPD_DDRA_CPU1_SDA")
		)
		(pad "6" smd rect
			(at -2.050034 -59.075066 90)
			(size 0.519938 1.4986)
			(layers "F.Cu" "F.Mask" "F.Paste")
			(net "GND")
		)
		(pad "7" smd rect
			(at -2.050034 -58.224928 90)
			(size 0.519938 1.4986)
			(layers "F.Cu" "F.Mask" "F.Paste")
			(net "M_A_CPU1_SA_DQ<0>")
		)
		(pad "8" smd rect
			(at -2.050034 -57.375044 90)
			(size 0.519938 1.4986)
			(layers "F.Cu" "F.Mask" "F.Paste")
			(net "GND")
		)
		(pad "9" smd rect
			(at -2.050034 -56.524906 90)
			(size 0.519938 1.4986)
			(layers "F.Cu" "F.Mask" "F.Paste")
			(net "M_A_CPU1_SA_DQ<1>")
		)
		(pad "10" smd rect
			(at -2.050034 -55.675022 90)
			(size 0.519938 1.4986)
			(layers "F.Cu" "F.Mask" "F.Paste")
			(net "GND")
		)
		(pad "11" smd rect
			(at -2.050034 -54.824884 90)
			(size 0.519938 1.4986)
			(layers "F.Cu" "F.Mask" "F.Paste")
			(net "M_A_CPU1_SA_DQS_DP<0>")
		)
		(pad "12" smd rect
			(at -2.050034 -53.975 90)
			(size 0.519938 1.4986)
			(layers "F.Cu" "F.Mask" "F.Paste")
			(net "M_A_CPU1_SA_DQS_DN<0>")
		)
		(pad "13" smd rect
			(at -2.050034 -53.125116 90)
			(size 0.519938 1.4986)
			(layers "F.Cu" "F.Mask" "F.Paste")
			(net "GND")
		)
		(pad "14" smd rect
			(at -2.050034 -52.274978 90)
			(size 0.519938 1.4986)
			(layers "F.Cu" "F.Mask" "F.Paste")
			(net "M_A_CPU1_SA_DQ<4>")
		)
		(pad "15" smd rect
			(at -2.050034 -51.425094 90)
			(size 0.519938 1.4986)
			(layers "F.Cu" "F.Mask" "F.Paste")
			(net "GND")
		)
		(pad "16" smd rect
			(at -2.050034 -50.574956 90)
			(size 0.519938 1.4986)
			(layers "F.Cu" "F.Mask" "F.Paste")
			(net "M_A_CPU1_SA_DQ<5>")
		)
		(pad "17" smd rect
			(at -2.050034 -49.725072 90)
			(size 0.519938 1.4986)
			(layers "F.Cu" "F.Mask" "F.Paste")
			(net "GND")
		)
		(pad "18" smd rect
			(at -2.050034 -48.874934 90)
			(size 0.519938 1.4986)
			(layers "F.Cu" "F.Mask" "F.Paste")
			(net "M_A_CPU1_SA_DQ<8>")
		)
		(pad "19" smd rect
			(at -2.050034 -48.02505 90)
			(size 0.519938 1.4986)
			(layers "F.Cu" "F.Mask" "F.Paste")
			(net "GND")
		)
		(pad "20" smd rect
			(at -2.050034 -47.174912 90)
			(size 0.519938 1.4986)
			(layers "F.Cu" "F.Mask" "F.Paste")
			(net "M_A_CPU1_SA_DQ<9>")
		)
		(pad "21" smd rect
			(at -2.050034 -46.325028 90)
			(size 0.519938 1.4986)
			(layers "F.Cu" "F.Mask" "F.Paste")
			(net "GND")
		)
		(pad "22" smd rect
			(at -2.050034 -45.47489 90)
			(size 0.519938 1.4986)
			(layers "F.Cu" "F.Mask" "F.Paste")
			(net "M_A_CPU1_SA_DQS_DP<1>")
		)
		(pad "23" smd rect
			(at -2.050034 -44.625006 90)
			(size 0.519938 1.4986)
			(layers "F.Cu" "F.Mask" "F.Paste")
			(net "M_A_CPU1_SA_DQS_DN<1>")
		)
		(pad "24" smd rect
			(at -2.050034 -43.775122 90)
			(size 0.519938 1.4986)
			(layers "F.Cu" "F.Mask" "F.Paste")
			(net "GND")
		)
		(pad "25" smd rect
			(at -2.050034 -42.924984 90)
			(size 0.519938 1.4986)
			(layers "F.Cu" "F.Mask" "F.Paste")
			(net "M_A_CPU1_SA_DQ<12>")
		)
		(pad "26" smd rect
			(at -2.050034 -42.0751 90)
			(size 0.519938 1.4986)
			(layers "F.Cu" "F.Mask" "F.Paste")
			(net "GND")
		)
		(pad "27" smd rect
			(at -2.050034 -41.224962 90)
			(size 0.519938 1.4986)
			(layers "F.Cu" "F.Mask" "F.Paste")
			(net "M_A_CPU1_SA_DQ<13>")
		)
		(pad "28" smd rect
			(at -2.050034 -40.375078 90)
			(size 0.519938 1.4986)
			(layers "F.Cu" "F.Mask" "F.Paste")
			(net "GND")
		)
		(pad "29" smd rect
			(at -2.050034 -39.52494 90)
			(size 0.519938 1.4986)
			(layers "F.Cu" "F.Mask" "F.Paste")
			(net "M_A_CPU1_SA_DQ<16>")
		)
		(pad "30" smd rect
			(at -2.050034 -38.675056 90)
			(size 0.519938 1.4986)
			(layers "F.Cu" "F.Mask" "F.Paste")
			(net "GND")
		)
		(pad "31" smd rect
			(at -2.050034 -37.824918 90)
			(size 0.519938 1.4986)
			(layers "F.Cu" "F.Mask" "F.Paste")
			(net "M_A_CPU1_SA_DQ<17>")
		)
		(pad "32" smd rect
			(at -2.050034 -36.975034 90)
			(size 0.519938 1.4986)
			(layers "F.Cu" "F.Mask" "F.Paste")
			(net "GND")
		)
		(pad "33" smd rect
			(at -2.050034 -36.124896 90)
			(size 0.519938 1.4986)
			(layers "F.Cu" "F.Mask" "F.Paste")
			(net "M_A_CPU1_SA_DQS_DP<2>")
		)
		(pad "34" smd rect
			(at -2.050034 -35.275012 90)
			(size 0.519938 1.4986)
			(layers "F.Cu" "F.Mask" "F.Paste")
			(net "M_A_CPU1_SA_DQS_DN<2>")
		)
		(pad "35" smd rect
			(at -2.050034 -34.425128 90)
			(size 0.519938 1.4986)
			(layers "F.Cu" "F.Mask" "F.Paste")
			(net "GND")
		)
		(pad "36" smd rect
			(at -2.050034 -33.57499 90)
			(size 0.519938 1.4986)
			(layers "F.Cu" "F.Mask" "F.Paste")
			(net "M_A_CPU1_SA_DQ<20>")
		)
		(pad "37" smd rect
			(at -2.050034 -32.725106 90)
			(size 0.519938 1.4986)
			(layers "F.Cu" "F.Mask" "F.Paste")
			(net "GND")
		)
		(pad "38" smd rect
			(at -2.050034 -31.874968 90)
			(size 0.519938 1.4986)
			(layers "F.Cu" "F.Mask" "F.Paste")
			(net "M_A_CPU1_SA_DQ<21>")
		)
		(pad "39" smd rect
			(at -2.050034 -31.025084 90)
			(size 0.519938 1.4986)
			(layers "F.Cu" "F.Mask" "F.Paste")
			(net "GND")
		)
		(pad "40" smd rect
			(at -2.050034 -30.174946 90)
			(size 0.519938 1.4986)
			(layers "F.Cu" "F.Mask" "F.Paste")
			(net "M_A_CPU1_SA_DQ<24>")
		)
		(pad "41" smd rect
			(at -2.050034 -29.325062 90)
			(size 0.519938 1.4986)
			(layers "F.Cu" "F.Mask" "F.Paste")
			(net "GND")
		)
		(pad "42" smd rect
			(at -2.050034 -28.474924 90)
			(size 0.519938 1.4986)
			(layers "F.Cu" "F.Mask" "F.Paste")
			(net "M_A_CPU1_SA_DQ<25>")
		)
		(pad "43" smd rect
			(at -2.050034 -27.62504 90)
			(size 0.519938 1.4986)
			(layers "F.Cu" "F.Mask" "F.Paste")
			(net "GND")
		)
		(pad "44" smd rect
			(at -2.050034 -26.774902 90)
			(size 0.519938 1.4986)
			(layers "F.Cu" "F.Mask" "F.Paste")
			(net "M_A_CPU1_SA_DQS_DP<3>")
		)
		(pad "45" smd rect
			(at -2.050034 -25.925018 90)
			(size 0.519938 1.4986)
			(layers "F.Cu" "F.Mask" "F.Paste")
			(net "M_A_CPU1_SA_DQS_DN<3>")
		)
		(pad "46" smd rect
			(at -2.050034 -25.07488 90)
			(size 0.519938 1.4986)
			(layers "F.Cu" "F.Mask" "F.Paste")
			(net "GND")
		)
		(pad "47" smd rect
			(at -2.050034 -24.224996 90)
			(size 0.519938 1.4986)
			(layers "F.Cu" "F.Mask" "F.Paste")
			(net "M_A_CPU1_SA_DQ<28>")
		)
		(pad "48" smd rect
			(at -2.050034 -23.375112 90)
			(size 0.519938 1.4986)
			(layers "F.Cu" "F.Mask" "F.Paste")
			(net "GND")
		)
		(pad "49" smd rect
			(at -2.050034 -22.524974 90)
			(size 0.519938 1.4986)
			(layers "F.Cu" "F.Mask" "F.Paste")
			(net "M_A_CPU1_SA_DQ<29>")
		)
		(pad "50" smd rect
			(at -2.050034 -21.67509 90)
			(size 0.519938 1.4986)
			(layers "F.Cu" "F.Mask" "F.Paste")
			(net "GND")
		)
		(pad "51" smd rect
			(at -2.050034 -20.824952 90)
			(size 0.519938 1.4986)
			(layers "F.Cu" "F.Mask" "F.Paste")
			(net "M_A_CPU1_SA_CB<0>")
		)
		(pad "52" smd rect
			(at -2.050034 -19.975068 90)
			(size 0.519938 1.4986)
			(layers "F.Cu" "F.Mask" "F.Paste")
			(net "GND")
		)
		(pad "53" smd rect
			(at -2.050034 -19.12493 90)
			(size 0.519938 1.4986)
			(layers "F.Cu" "F.Mask" "F.Paste")
			(net "M_A_CPU1_SA_CB<1>")
		)
		(pad "54" smd rect
			(at -2.050034 -18.275046 90)
			(size 0.519938 1.4986)
			(layers "F.Cu" "F.Mask" "F.Paste")
			(net "GND")
		)
		(pad "55" smd rect
			(at -2.050034 -17.424908 90)
			(size 0.519938 1.4986)
			(layers "F.Cu" "F.Mask" "F.Paste")
			(net "M_A_CPU1_SA_DQS_DP<4>")
		)
		(pad "56" smd rect
			(at -2.050034 -16.575024 90)
			(size 0.519938 1.4986)
			(layers "F.Cu" "F.Mask" "F.Paste")
			(net "M_A_CPU1_SA_DQS_DN<4>")
		)
		(pad "57" smd rect
			(at -2.050034 -15.724886 90)
			(size 0.519938 1.4986)
			(layers "F.Cu" "F.Mask" "F.Paste")
			(net "GND")
		)
		(pad "58" smd rect
			(at -2.050034 -14.875002 90)
			(size 0.519938 1.4986)
			(layers "F.Cu" "F.Mask" "F.Paste")
			(net "M_A_CPU1_SA_CB<4>")
		)
		(pad "59" smd rect
			(at -2.050034 -14.025118 90)
			(size 0.519938 1.4986)
			(layers "F.Cu" "F.Mask" "F.Paste")
			(net "GND")
		)
		(pad "60" smd rect
			(at -2.050034 -13.17498 90)
			(size 0.519938 1.4986)
			(layers "F.Cu" "F.Mask" "F.Paste")
			(net "M_A_CPU1_SA_CB<5>")
		)
		(pad "61" smd rect
			(at -2.050034 -12.325096 90)
			(size 0.519938 1.4986)
			(layers "F.Cu" "F.Mask" "F.Paste")
			(net "GND")
		)
		(pad "62" smd rect
			(at -2.050034 -11.474958 90)
			(size 0.519938 1.4986)
			(layers "F.Cu" "F.Mask" "F.Paste")
			(net "M_A_CPU1_ALERT_N")
		)
		(pad "63" smd rect
			(at -2.050034 -10.625074 90)
			(size 0.519938 1.4986)
			(layers "F.Cu" "F.Mask" "F.Paste")
			(net "GND")
		)
		(pad "64" smd rect
			(at -2.050034 -9.774936 90)
			(size 0.519938 1.4986)
			(layers "F.Cu" "F.Mask" "F.Paste")
			(net "M_A_CPU1_SA_CS_N<0>")
		)
		(pad "65" smd rect
			(at -2.050034 -8.925052 90)
			(size 0.519938 1.4986)
			(layers "F.Cu" "F.Mask" "F.Paste")
			(net "GND")
		)
		(pad "66" smd rect
			(at -2.050034 -8.074914 90)
			(size 0.519938 1.4986)
			(layers "F.Cu" "F.Mask" "F.Paste")
			(net "M_A_CPU1_SA_CA<0>")
		)
		(pad "67" smd rect
			(at -2.050034 -7.22503 90)
			(size 0.519938 1.4986)
			(layers "F.Cu" "F.Mask" "F.Paste")
			(net "GND")
		)
		(pad "68" smd rect
			(at -2.050034 -6.374892 90)
			(size 0.519938 1.4986)
			(layers "F.Cu" "F.Mask" "F.Paste")
			(net "M_A_CPU1_SA_CA<2>")
		)
		(pad "69" smd rect
			(at -2.050034 -5.525008 90)
			(size 0.519938 1.4986)
			(layers "F.Cu" "F.Mask" "F.Paste")
			(net "GND")
		)
		(pad "70" smd rect
			(at -2.050034 -4.675124 90)
			(size 0.519938 1.4986)
			(layers "F.Cu" "F.Mask" "F.Paste")
			(net "M_A_CPU1_SA_CA<4>")
		)
		(pad "71" smd rect
			(at -2.050034 -3.824986 90)
			(size 0.519938 1.4986)
			(layers "F.Cu" "F.Mask" "F.Paste")
			(net "GND")
		)
		(pad "72" smd rect
			(at -2.050034 -2.975102 90)
			(size 0.519938 1.4986)
			(layers "F.Cu" "F.Mask" "F.Paste")
			(net "M_A_CPU1_SA_CA<6>")
		)
		(pad "73" smd rect
			(at -2.050034 -2.124964 90)
			(size 0.519938 1.4986)
			(layers "F.Cu" "F.Mask" "F.Paste")
			(net "GND")
		)
		(pad "74" smd rect
			(at -2.050034 -1.27508 90)
			(size 0.519938 1.4986)
			(layers "F.Cu" "F.Mask" "F.Paste")
			(net "M_A_CPU1_SA_PAR")
		)
		(pad "75" smd rect
			(at -2.050034 -0.424942 90)
			(size 0.519938 1.4986)
			(layers "F.Cu" "F.Mask" "F.Paste")
			(net "GND")
		)
		(pad "76" smd rect
			(at -2.050034 5.525008 90)
			(size 0.519938 1.4986)
			(layers "F.Cu" "F.Mask" "F.Paste")
			(net "M_A_CPU1_SB_CA<0>")
		)
		(pad "77" smd rect
			(at -2.050034 6.374892 90)
			(size 0.519938 1.4986)
			(layers "F.Cu" "F.Mask" "F.Paste")
			(net "GND")
		)
		(pad "78" smd rect
			(at -2.050034 7.22503 90)
			(size 0.519938 1.4986)
			(layers "F.Cu" "F.Mask" "F.Paste")
			(net "M_A_CPU1_SB_CA<2>")
		)
		(pad "79" smd rect
			(at -2.050034 8.074914 90)
			(size 0.519938 1.4986)
			(layers "F.Cu" "F.Mask" "F.Paste")
			(net "GND")
		)
		(pad "80" smd rect
			(at -2.050034 8.925052 90)
			(size 0.519938 1.4986)
			(layers "F.Cu" "F.Mask" "F.Paste")
			(net "M_A_CPU1_SB_CA<4>")
		)
		(pad "81" smd rect
			(at -2.050034 9.774936 90)
			(size 0.519938 1.4986)
			(layers "F.Cu" "F.Mask" "F.Paste")
			(net "GND")
		)
		(pad "82" smd rect
			(at -2.050034 10.625074 90)
			(size 0.519938 1.4986)
			(layers "F.Cu" "F.Mask" "F.Paste")
			(net "M_A_CPU1_SB_CA<6>")
		)
		(pad "83" smd rect
			(at -2.050034 11.474958 90)
			(size 0.519938 1.4986)
			(layers "F.Cu" "F.Mask" "F.Paste")
			(net "GND")
		)
		(pad "84" smd rect
			(at -2.050034 12.325096 90)
			(size 0.519938 1.4986)
			(layers "F.Cu" "F.Mask" "F.Paste")
			(net "M_A_CPU1_SB_CS_N<0>")
		)
		(pad "85" smd rect
			(at -2.050034 13.17498 90)
			(size 0.519938 1.4986)
			(layers "F.Cu" "F.Mask" "F.Paste")
			(net "GND")
		)
		(pad "86" smd rect
			(at -2.050034 14.025118 90)
			(size 0.519938 1.4986)
			(layers "F.Cu" "F.Mask" "F.Paste")
			(net "M_A_CPU1_SA_RSP<0>")
		)
		(pad "87" smd rect
			(at -2.050034 14.875002 90)
			(size 0.519938 1.4986)
			(layers "F.Cu" "F.Mask" "F.Paste")
			(net "M_A_CPU1_SB_RSP<0>")
		)
		(pad "88" smd rect
			(at -2.050034 15.724886 90)
			(size 0.519938 1.4986)
			(layers "F.Cu" "F.Mask" "F.Paste")
			(net "GND")
		)
		(pad "89" smd rect
			(at -2.050034 16.575024 90)
			(size 0.519938 1.4986)
			(layers "F.Cu" "F.Mask" "F.Paste")
			(net "M_A_CPU1_SB_CB<4>")
		)
		(pad "90" smd rect
			(at -2.050034 17.424908 90)
			(size 0.519938 1.4986)
			(layers "F.Cu" "F.Mask" "F.Paste")
			(net "GND")
		)
		(pad "91" smd rect
			(at -2.050034 18.275046 90)
			(size 0.519938 1.4986)
			(layers "F.Cu" "F.Mask" "F.Paste")
			(net "M_A_CPU1_SB_CB<5>")
		)
		(pad "92" smd rect
			(at -2.050034 19.12493 90)
			(size 0.519938 1.4986)
			(layers "F.Cu" "F.Mask" "F.Paste")
			(net "GND")
		)
		(pad "93" smd rect
			(at -2.050034 19.975068 90)
			(size 0.519938 1.4986)
			(layers "F.Cu" "F.Mask" "F.Paste")
			(net "M_A_CPU1_SB_DQS_DP<9>")
		)
		(pad "94" smd rect
			(at -2.050034 20.824952 90)
			(size 0.519938 1.4986)
			(layers "F.Cu" "F.Mask" "F.Paste")
			(net "M_A_CPU1_SB_DQS_DN<9>")
		)
		(pad "95" smd rect
			(at -2.050034 21.67509 90)
			(size 0.519938 1.4986)
			(layers "F.Cu" "F.Mask" "F.Paste")
			(net "GND")
		)
		(pad "96" smd rect
			(at -2.050034 22.524974 90)
			(size 0.519938 1.4986)
			(layers "F.Cu" "F.Mask" "F.Paste")
			(net "M_A_CPU1_SB_CB<0>")
		)
		(pad "97" smd rect
			(at -2.050034 23.375112 90)
			(size 0.519938 1.4986)
			(layers "F.Cu" "F.Mask" "F.Paste")
			(net "GND")
		)
		(pad "98" smd rect
			(at -2.050034 24.224996 90)
			(size 0.519938 1.4986)
			(layers "F.Cu" "F.Mask" "F.Paste")
			(net "M_A_CPU1_SB_CB<1>")
		)
		(pad "99" smd rect
			(at -2.050034 25.07488 90)
			(size 0.519938 1.4986)
			(layers "F.Cu" "F.Mask" "F.Paste")
			(net "GND")
		)
		(pad "100" smd rect
			(at -2.050034 25.925018 90)
			(size 0.519938 1.4986)
			(layers "F.Cu" "F.Mask" "F.Paste")
			(net "M_A_CPU1_SB_DQ<0>")
		)
		(pad "101" smd rect
			(at -2.050034 26.774902 90)
			(size 0.519938 1.4986)
			(layers "F.Cu" "F.Mask" "F.Paste")
			(net "GND")
		)
		(pad "102" smd rect
			(at -2.050034 27.62504 90)
			(size 0.519938 1.4986)
			(layers "F.Cu" "F.Mask" "F.Paste")
			(net "M_A_CPU1_SB_DQ<1>")
		)
		(pad "103" smd rect
			(at -2.050034 28.474924 90)
			(size 0.519938 1.4986)
			(layers "F.Cu" "F.Mask" "F.Paste")
			(net "GND")
		)
		(pad "104" smd rect
			(at -2.050034 29.325062 90)
			(size 0.519938 1.4986)
			(layers "F.Cu" "F.Mask" "F.Paste")
			(net "M_A_CPU1_SB_DQS_DP<0>")
		)
		(pad "105" smd rect
			(at -2.050034 30.174946 90)
			(size 0.519938 1.4986)
			(layers "F.Cu" "F.Mask" "F.Paste")
			(net "M_A_CPU1_SB_DQS_DN<0>")
		)
		(pad "106" smd rect
			(at -2.050034 31.025084 90)
			(size 0.519938 1.4986)
			(layers "F.Cu" "F.Mask" "F.Paste")
			(net "GND")
		)
		(pad "107" smd rect
			(at -2.050034 31.874968 90)
			(size 0.519938 1.4986)
			(layers "F.Cu" "F.Mask" "F.Paste")
			(net "M_A_CPU1_SB_DQ<4>")
		)
		(pad "108" smd rect
			(at -2.050034 32.725106 90)
			(size 0.519938 1.4986)
			(layers "F.Cu" "F.Mask" "F.Paste")
			(net "GND")
		)
		(pad "109" smd rect
			(at -2.050034 33.57499 90)
			(size 0.519938 1.4986)
			(layers "F.Cu" "F.Mask" "F.Paste")
			(net "M_A_CPU1_SB_DQ<5>")
		)
		(pad "110" smd rect
			(at -2.050034 34.425128 90)
			(size 0.519938 1.4986)
			(layers "F.Cu" "F.Mask" "F.Paste")
			(net "GND")
		)
		(pad "111" smd rect
			(at -2.050034 35.275012 90)
			(size 0.519938 1.4986)
			(layers "F.Cu" "F.Mask" "F.Paste")
			(net "M_A_CPU1_SB_DQ<8>")
		)
		(pad "112" smd rect
			(at -2.050034 36.124896 90)
			(size 0.519938 1.4986)
			(layers "F.Cu" "F.Mask" "F.Paste")
			(net "GND")
		)
		(pad "113" smd rect
			(at -2.050034 36.975034 90)
			(size 0.519938 1.4986)
			(layers "F.Cu" "F.Mask" "F.Paste")
			(net "M_A_CPU1_SB_DQ<9>")
		)
	)
)
